# BASEBOARD_FAB2 (Tioga Pass) — schematic netlist excerpt (pin names and nets, part order shuffled) for the footprints in the layout excerpt that follows; sources: Cadence DE-HDL packaged netlist, KiCad conversion of Wiwynn_Tioga_Pass_MB.brd

C4C6  CAP  1.0UF 16V 10% X6S  pkg 0402  page 205 : A = VR_PVSA_CPU0_VCIN ; B = GND
R7A13  RES  100.0 1% CHIP  pkg 0402  page 236 : A = VSENSE_PVNN_PCH_STBY_AVSP ; B = PVNN_PCH_STBY
R8A10  RES  5.11K 1% CHIP  pkg 0402  page 237 : A = P3V3_STBY ; B = PWRGD_P1V8_PCH_STBY_R

(kicad_pcb
	(version 20260206)
	(generator "pcbnew")
	(generator_version "10.0")
	(general
		(thickness 1.6)
		(legacy_teardrops no)
	)
	(paper "A4")
	(title_block
		(title "Wiwynn_Tioga_Pass_MB.brd")
		(comment 1 "Tioga Pass / footprints 1199-1201 of 4770")
	)
	(layers
		(0 "F.Cu" signal "TOP")
		(4 "In1.Cu" signal "L2GND")
		(6 "In2.Cu" signal "L3")
		(8 "In3.Cu" signal "L4GND")
		(10 "In4.Cu" signal "L5")
		(12 "In5.Cu" signal "L6GND")
		(14 "In6.Cu" signal "L7VCC")
		(16 "In7.Cu" signal "L8VCC")
		(18 "In8.Cu" signal "L9GND")
		(20 "In9.Cu" signal "L10")
		(22 "In10.Cu" signal "L11GND")
		(24 "In11.Cu" signal "L12")
		(26 "In12.Cu" signal "L13GND")
		(2 "B.Cu" signal "BOTTOM")
		(9 "F.Adhes" user "F.Adhesive")
		(11 "B.Adhes" user "B.Adhesive")
		(13 "F.Paste" user "Package Geometry/Pastemask Top")
		(15 "B.Paste" user "Package Geometry/Pastemask Bottom")
		(5 "F.SilkS" user "Ref Des/Silkscreen Top")
		(7 "B.SilkS" user "Ref Des/Silkscreen Bottom")
		(1 "F.Mask" user "Board Geometry/Soldermask Top")
		(3 "B.Mask" user "Board Geometry/Soldermask Bottom")
		(17 "Dwgs.User" user "User.Drawings")
		(19 "Cmts.User" user "User.Comments")
		(21 "Eco1.User" user "User.Eco1")
		(23 "Eco2.User" user "User.Eco2")
		(25 "Edge.Cuts" user "Board Geometry/Outline")
		(27 "Margin" user)
		(31 "F.CrtYd" user "Package Geometry/Place Bound Top")
		(29 "B.CrtYd" user "Package Geometry/Place Bound Bottom")
		(35 "F.Fab" user "Ref Des/Assembly Top")
		(33 "B.Fab" user "Ref Des/Assembly Bottom")
	)
	(footprint ""
		(layer "F.Cu")
		(at 406.172416 -149.452584 -90)
		(property "Reference" "R8A10"
			(at 0 0 270)
			(layer "F.SilkS")
			(hide yes)
			(effects
				(font
					(size 1.27 1.27)
				)
			)
		)
		(property "Value" ""
			(at 0 0 270)
			(layer "F.Fab")
			(effects
				(font
					(size 1.27 1.27)
				)
			)
		)
		(duplicate_pad_numbers_are_jumpers no)
		(fp_poly
			(pts
				(xy -0.2794 -0.1016) (xy 0.2794 -0.1016) (xy 0.2794 0.9906) (xy -0.2794 0.9906)
			)
			(stroke
				(width 0)
				(type default)
			)
			(fill no)
			(layer "F.CrtYd")
		)
		(fp_line
			(start -0.2794 0.9906)
			(end 0.2794 0.9906)
			(stroke
				(width 0.1)
				(type default)
			)
			(layer "F.Fab")
		)
		(fp_line
			(start 0.2794 0.9906)
			(end 0.2794 -0.1016)
			(stroke
				(width 0.1)
				(type default)
			)
			(layer "F.Fab")
		)
		(fp_line
			(start -0.2794 -0.1016)
			(end -0.2794 0.9906)
			(stroke
				(width 0.1)
				(type default)
			)
			(layer "F.Fab")
		)
		(fp_line
			(start 0.2794 -0.1016)
			(end -0.2794 -0.1016)
			(stroke
				(width 0.1)
				(type default)
			)
			(layer "F.Fab")
		)
		(pad "1" smd rect
			(at 0 0 270)
			(size 0.508 0.508)
			(layers "F.Cu" "F.Mask" "F.Paste")
			(net "P3V3_STBY")
		)
		(pad "2" smd rect
			(at 0 0.889 270)
			(size 0.508 0.508)
			(layers "F.Cu" "F.Mask" "F.Paste")
			(net "PWRGD_P1V8_PCH_STBY_R")
		)
		(zone
			(layer "F.Cu")
			(hatch none 0.5)
			(connect_pads
				(clearance 0)
			)
			(min_thickness 0.25)
			(keepout
				(tracks not_allowed)
				(vias allowed)
				(pads allowed)
				(copperpour not_allowed)
				(footprints allowed)
			)
			(placement
				(enabled no)
				(sheetname "")
			)
			(fill
				(thermal_gap 0.5)
				(thermal_bridge_width 0.5)
				(island_removal_mode 0)
			)
			(polygon
				(pts
					(xy 405.537416 -149.706584) (xy 405.537416 -149.198584) (xy 405.918416 -149.198584) (xy 405.918416 -149.706584)
				)
			)
		)
		(zone
			(layer "F.Cu")
			(hatch none 0.5)
			(connect_pads
				(clearance 0)
			)
			(min_thickness 0.25)
			(keepout
				(tracks allowed)
				(vias not_allowed)
				(pads allowed)
				(copperpour not_allowed)
				(footprints allowed)
			)
			(placement
				(enabled no)
				(sheetname "")
			)
			(fill
				(thermal_gap 0.5)
				(thermal_bridge_width 0.5)
				(island_removal_mode 0)
			)
			(polygon
				(pts
					(xy 405.918416 -149.706584) (xy 405.918416 -149.198584) (xy 405.537416 -149.198584) (xy 405.537416 -149.706584)
				)
			)
		)
	)
	(footprint ""
		(layer "F.Cu")
		(at 197.226428 -93.734382 -90)
		(property "Reference" "C4C6"
			(at 0 0 270)
			(layer "F.SilkS")
			(hide yes)
			(effects
				(font
					(size 1.27 1.27)
				)
			)
		)
		(property "Value" ""
			(at 0 0 270)
			(layer "F.Fab")
			(effects
				(font
					(size 1.27 1.27)
				)
			)
		)
		(duplicate_pad_numbers_are_jumpers no)
		(fp_poly
			(pts
				(xy 0.3048 -0.1016) (xy 0.3048 0.9906) (xy -0.3048 0.9906) (xy -0.3048 -0.1016)
			)
			(stroke
				(width 0)
				(type default)
			)
			(fill no)
			(layer "F.CrtYd")
		)
		(fp_line
			(start -0.3048 0.9906)
			(end 0.3048 0.9906)
			(stroke
				(width 0.1)
				(type default)
			)
			(layer "F.Fab")
		)
		(fp_line
			(start 0.3048 0.9906)
			(end 0.3048 -0.1016)
			(stroke
				(width 0.1)
				(type default)
			)
			(layer "F.Fab")
		)
		(fp_line
			(start -0.3048 -0.1016)
			(end -0.3048 0.9906)
			(stroke
				(width 0.1)
				(type default)
			)
			(layer "F.Fab")
		)
		(fp_line
			(start 0.3048 -0.1016)
			(end -0.3048 -0.1016)
			(stroke
				(width 0.1)
				(type default)
			)
			(layer "F.Fab")
		)
		(pad "1" smd rect
			(at 0 0 270)
			(size 0.508 0.508)
			(layers "F.Cu" "F.Mask" "F.Paste")
			(net "VR_PVSA_CPU0_VCIN")
		)
		(pad "2" smd rect
			(at 0 0.889 270)
			(size 0.508 0.508)
			(layers "F.Cu" "F.Mask" "F.Paste")
			(net "GND")
		)
		(zone
			(layer "F.Cu")
			(hatch none 0.5)
			(connect_pads
				(clearance 0)
			)
			(min_thickness 0.25)
			(keepout
				(tracks not_allowed)
				(vias allowed)
				(pads allowed)
				(copperpour not_allowed)
				(footprints allowed)
			)
			(placement
				(enabled no)
				(sheetname "")
			)
			(fill
				(thermal_gap 0.5)
				(thermal_bridge_width 0.5)
				(island_removal_mode 0)
			)
			(polygon
				(pts
					(xy 196.591428 -93.988382) (xy 196.591428 -93.480382) (xy 196.972428 -93.480382) (xy 196.972428 -93.988382)
				)
			)
		)
		(zone
			(layer "F.Cu")
			(hatch none 0.5)
			(connect_pads
				(clearance 0)
			)
			(min_thickness 0.25)
			(keepout
				(tracks allowed)
				(vias not_allowed)
				(pads allowed)
				(copperpour not_allowed)
				(footprints allowed)
			)
			(placement
				(enabled no)
				(sheetname "")
			)
			(fill
				(thermal_gap 0.5)
				(thermal_bridge_width 0.5)
				(island_removal_mode 0)
			)
			(polygon
				(pts
					(xy 196.972428 -93.988382) (xy 196.972428 -93.480382) (xy 196.591428 -93.480382) (xy 196.591428 -93.988382)
				)
			)
		)
	)
	(footprint ""
		(layer "F.Cu")
		(at 368.808 -137.3124)
		(property "Reference" "R7A13"
			(at 0 0 0)
			(layer "F.SilkS")
			(hide yes)
			(effects
				(font
					(size 1.27 1.27)
				)
			)
		)
		(property "Value" ""
			(at 0 0 0)
			(layer "F.Fab")
			(effects
				(font
					(size 1.27 1.27)
				)
			)
		)
		(duplicate_pad_numbers_are_jumpers no)
		(fp_poly
			(pts
				(xy -0.2794 -0.1016) (xy 0.2794 -0.1016) (xy 0.2794 0.9906) (xy -0.2794 0.9906)
			)
			(stroke
				(width 0)
				(type default)
			)
			(fill no)
			(layer "F.CrtYd")
		)
		(fp_line
			(start -0.2794 -0.1016)
			(end -0.2794 0.9906)
			(stroke
				(width 0.1)
				(type default)
			)
			(layer "F.Fab")
		)
		(fp_line
			(start -0.2794 0.9906)
			(end 0.2794 0.9906)
			(stroke
				(width 0.1)
				(type default)
			)
			(layer "F.Fab")
		)
		(fp_line
			(start 0.2794 -0.1016)
			(end -0.2794 -0.1016)
			(stroke
				(width 0.1)
				(type default)
			)
			(layer "F.Fab")
		)
		(fp_line
			(start 0.2794 0.9906)
			(end 0.2794 -0.1016)
			(stroke
				(width 0.1)
				(type default)
			)
			(layer "F.Fab")
		)
		(pad "1" smd rect
			(at 0 0)
			(size 0.508 0.508)
			(layers "F.Cu" "F.Mask" "F.Paste")
			(net "VSENSE_PVNN_PCH_STBY_AVSP")
		)
		(pad "2" smd rect
			(at 0 0.889)
			(size 0.508 0.508)
			(layers "F.Cu" "F.Mask" "F.Paste")
			(net "PVNN_PCH_STBY")
		)
		(zone
			(layer "F.Cu")
			(hatch none 0.5)
			(connect_pads
				(clearance 0)
			)
			(min_thickness 0.25)
			(keepout
				(tracks allowed)
				(vias not_allowed)
				(pads allowed)
				(copperpour not_allowed)
				(footprints allowed)
			)
			(placement
				(enabled no)
				(sheetname "")
			)
			(fill
				(thermal_gap 0.5)
				(thermal_bridge_width 0.5)
				(island_removal_mode 0)
			)
			(polygon
				(pts
					(xy 368.554 -137.0584) (xy 369.062 -137.0584) (xy 369.062 -136.6774) (xy 368.554 -136.6774)
				)
			)
		)
		(zone
			(layer "F.Cu")
			(hatch none 0.5)
			(connect_pads
				(clearance 0)
			)
			(min_thickness 0.25)
			(keepout
				(tracks not_allowed)
				(vias allowed)
				(pads allowed)
				(copperpour not_allowed)
				(footprints allowed)
			)
			(placement
				(enabled no)
				(sheetname "")
			)
			(fill
				(thermal_gap 0.5)
				(thermal_bridge_width 0.5)
				(island_removal_mode 0)
			)
			(polygon
				(pts
					(xy 368.554 -136.6774) (xy 369.062 -136.6774) (xy 369.062 -137.0584) (xy 368.554 -137.0584)
				)
			)
		)
	)
)
